(kicad_pcb
	(version 20260206)
	(generator "pcbnew")
	(generator_version "10.0")
	(general
		(thickness 1.6)
		(legacy_teardrops no)
	)
	(paper "A4")
	(title_block
		(title "Bryce Canyon_F.DPB_16315-1-OCP.brd")
		(comment 1 "Bryce Canyon / footprints 374-381 of 2223")
	)
	(layers
		(0 "F.Cu" signal "TOP")
		(4 "In1.Cu" signal "L2GND")
		(6 "In2.Cu" signal "L3")
		(8 "In3.Cu" signal "L4GND")
		(10 "In4.Cu" signal "L5")
		(12 "In5.Cu" signal "L6VCC")
		(14 "In6.Cu" signal "L7VCC")
		(16 "In7.Cu" signal "L8")
		(18 "In8.Cu" signal "L9GND")
		(20 "In9.Cu" signal "L10")
		(22 "In10.Cu" signal "L11GND")
		(2 "B.Cu" signal "BOTTOM")
		(9 "F.Adhes" user "F.Adhesive")
		(11 "B.Adhes" user "B.Adhesive")
		(13 "F.Paste" user "Package Geometry/Pastemask Top")
		(15 "B.Paste" user "Package Geometry/Pastemask Bottom")
		(5 "F.SilkS" user "Ref Des/Silkscreen Top")
		(7 "B.SilkS" user "Ref Des/Silkscreen Bottom")
		(1 "F.Mask" user "Board Geometry/Soldermask Top")
		(3 "B.Mask" user "Board Geometry/Soldermask Bottom")
		(17 "Dwgs.User" user "User.Drawings")
		(19 "Cmts.User" user "User.Comments")
		(21 "Eco1.User" user "User.Eco1")
		(23 "Eco2.User" user "User.Eco2")
		(25 "Edge.Cuts" user "Board Geometry/Outline")
		(27 "Margin" user)
		(31 "F.CrtYd" user "Package Geometry/Place Bound Top")
		(29 "B.CrtYd" user "Package Geometry/Place Bound Bottom")
		(35 "F.Fab" user "Ref Des/Assembly Top")
		(33 "B.Fab" user "Ref Des/Assembly Bottom")
	)
	(footprint ""
		(layer "F.Cu")
		(at 228.419152 -390.33704)
		(property "Reference" "Q9"
			(at 0 0 0)
			(layer "F.SilkS")
			(hide yes)
			(effects
				(font
					(size 1.27 1.27)
				)
			)
		)
		(property "Value" "MMBT3904TT1G-GP"
			(at 0 -9.7282 0)
			(unlocked yes)
			(layer "F.Fab")
			(hide yes)
			(effects
				(font
					(size 1.016 1.016)
					(thickness 0.1524)
				)
			)
		)
		(property "Device Type" "SC75CBE1D6H36"
			(at 0 -11.6332 0)
			(unlocked yes)
			(layer "F.Fab")
			(hide yes)
			(effects
				(font
					(size 1.016 1.016)
					(thickness 0.1524)
				)
			)
		)
		(duplicate_pad_numbers_are_jumpers no)
		(fp_line
			(start -0.9652 -1.3716)
			(end -0.9652 1.3716)
			(stroke
				(width 0.1524)
				(type default)
			)
			(layer "F.SilkS")
		)
		(fp_line
			(start -0.9652 1.3716)
			(end 0.9652 1.3716)
			(stroke
				(width 0.1524)
				(type default)
			)
			(layer "F.SilkS")
		)
		(fp_line
			(start 0.9652 -1.3716)
			(end -0.9652 -1.3716)
			(stroke
				(width 0.1524)
				(type default)
			)
			(layer "F.SilkS")
		)
		(fp_line
			(start 0.9652 1.3716)
			(end 0.9652 -1.3716)
			(stroke
				(width 0.1524)
				(type default)
			)
			(layer "F.SilkS")
		)
		(fp_rect
			(start -1.0414 1.4478)
			(end 1.0414 -1.4478)
			(stroke
				(width 0)
				(type default)
			)
			(fill no)
			(layer "F.CrtYd")
		)
		(fp_poly
			(pts
				(xy -1.0414 -1.4478) (xy 1.0414 -1.4478) (xy 1.0414 1.4478) (xy -1.0414 1.4478)
			)
			(stroke
				(width 0)
				(type default)
			)
			(fill no)
			(layer "F.Fab")
		)
		(pad "B" smd custom
			(at -0.508 0.7112)
			(size 0.127 0.127)
			(layers "F.Cu" "F.Mask" "F.Paste")
			(net "VCCP_IN")
			(options
				(clearance outline)
				(anchor circle)
			)
			(primitives
				(gr_poly
					(pts
						(arc
							(start -0.044958 0.4572)
							(mid -0.192463 0.399794)
							(end -0.254 0.254)
						)
						(xy -0.254 -0.254)
						(arc
							(start -0.253746 -0.254)
							(mid -0.192968 -0.398936)
							(end -0.04699 -0.4572)
						)
						(arc
							(start 0.04699 -0.4572)
							(mid 0.192989 -0.398958)
							(end 0.253746 -0.254)
						)
						(xy 0.254 -0.254)
						(arc
							(start 0.254 0.254)
							(mid 0.192404 0.399734)
							(end 0.044958 0.4572)
						)
					)
					(width 0)
					(fill yes)
				)
			)
		)
		(pad "C" smd custom
			(at 0 -0.7112)
			(size 0.127 0.127)
			(layers "F.Cu" "F.Mask" "F.Paste")
			(net "P12V_IN")
			(options
				(clearance outline)
				(anchor circle)
			)
			(primitives
				(gr_poly
					(pts
						(arc
							(start -0.044958 0.4572)
							(mid -0.192463 0.399794)
							(end -0.254 0.254)
						)
						(xy -0.254 -0.254)
						(arc
							(start -0.253746 -0.254)
							(mid -0.192968 -0.398936)
							(end -0.04699 -0.4572)
						)
						(arc
							(start 0.04699 -0.4572)
							(mid 0.192989 -0.398958)
							(end 0.253746 -0.254)
						)
						(xy 0.254 -0.254)
						(arc
							(start 0.254 0.254)
							(mid 0.192404 0.399734)
							(end 0.044958 0.4572)
						)
					)
					(width 0)
					(fill yes)
				)
			)
		)
		(pad "E" smd custom
			(at 0.508 0.7112)
			(size 0.127 0.127)
			(layers "F.Cu" "F.Mask" "F.Paste")
			(net "P3V3_IN_BIAS")
			(options
				(clearance outline)
				(anchor circle)
			)
			(primitives
				(gr_poly
					(pts
						(arc
							(start -0.044958 0.4572)
							(mid -0.192463 0.399794)
							(end -0.254 0.254)
						)
						(xy -0.254 -0.254)
						(arc
							(start -0.253746 -0.254)
							(mid -0.192968 -0.398936)
							(end -0.04699 -0.4572)
						)
						(arc
							(start 0.04699 -0.4572)
							(mid 0.192989 -0.398958)
							(end 0.253746 -0.254)
						)
						(xy 0.254 -0.254)
						(arc
							(start 0.254 0.254)
							(mid 0.192404 0.399734)
							(end 0.044958 0.4572)
						)
					)
					(width 0)
					(fill yes)
				)
			)
		)
	)
	(footprint ""
		(layer "F.Cu")
		(at 55.486046 -186.287918)
		(property "Reference" "C214"
			(at 0 0 0)
			(layer "F.SilkS")
			(hide yes)
			(effects
				(font
					(size 1.27 1.27)
				)
			)
		)
		(property "Value" "SC4D7U25V5KX-1-GP"
			(at -0.0762 -6.1214 0)
			(unlocked yes)
			(layer "F.Fab")
			(hide yes)
			(effects
				(font
					(size 1.016 1.016)
					(thickness 0.1524)
				)
			)
		)
		(property "Device Type" "C805H58"
			(at -0.0762 -8.1534 0)
			(unlocked yes)
			(layer "F.Fab")
			(hide yes)
			(effects
				(font
					(size 1.016 1.016)
					(thickness 0.1524)
				)
			)
		)
		(duplicate_pad_numbers_are_jumpers no)
		(fp_line
			(start 0.635 0)
			(end -0.635 0)
			(stroke
				(width 0.508)
				(type default)
			)
			(layer "F.SilkS")
		)
		(fp_rect
			(start -0.9652 1.778)
			(end 0.9652 -1.778)
			(stroke
				(width 0)
				(type default)
			)
			(fill no)
			(layer "F.CrtYd")
		)
		(fp_poly
			(pts
				(xy -0.9652 -1.778) (xy 0.9652 -1.778) (xy 0.9652 1.778) (xy -0.9652 1.778)
			)
			(stroke
				(width 0)
				(type default)
			)
			(fill no)
			(layer "F.Fab")
		)
		(pad "1" smd rect
			(at 0 -0.9652)
			(size 1.397 1.143)
			(layers "F.Cu" "F.Mask" "F.Paste")
			(net "P12V_HDD13")
		)
		(pad "2" smd rect
			(at 0 0.9652)
			(size 1.397 1.143)
			(layers "F.Cu" "F.Mask" "F.Paste")
			(net "GND")
		)
	)
	(footprint ""
		(layer "F.Cu")
		(at 271.19707 -8.936228 180)
		(property "Reference" "TP193"
			(at 0 0 180)
			(layer "F.SilkS")
			(hide yes)
			(effects
				(font
					(size 1.27 1.27)
				)
			)
		)
		(property "Value" "TPAD32-GP"
			(at -0.0508 -1.6764 180)
			(unlocked yes)
			(layer "F.Fab")
			(hide yes)
			(effects
				(font
					(size 1.016 1.016)
					(thickness 0.1524)
				)
			)
		)
		(property "Device Type" "TPAD32"
			(at -0.0508 -3.2004 180)
			(unlocked yes)
			(layer "F.Fab")
			(hide yes)
			(effects
				(font
					(size 1.016 1.016)
					(thickness 0.1524)
				)
			)
		)
		(duplicate_pad_numbers_are_jumpers no)
		(fp_poly
			(pts
				(arc
					(start -0.4064 0)
					(mid 0.4064 0)
					(end -0.4064 0)
				)
			)
			(stroke
				(width 0)
				(type default)
			)
			(fill no)
			(layer "F.CrtYd")
		)
		(fp_poly
			(pts
				(arc
					(start -0.7112 0)
					(mid 0.7112 0)
					(end -0.7112 0)
				)
			)
			(stroke
				(width 0)
				(type default)
			)
			(fill no)
			(layer "F.Fab")
		)
		(pad "1" smd circle
			(at 0 0 180)
			(size 0.8128 0.8128)
			(layers "F.Cu" "F.Mask" "F.Paste")
			(net "TP_COMP_B_NCSI_RXD0")
		)
	)
	(footprint ""
		(layer "F.Cu")
		(at 444.1952 -250.825 90)
		(property "Reference" "C632"
			(at 0 0 90)
			(layer "F.SilkS")
			(hide yes)
			(effects
				(font
					(size 1.27 1.27)
				)
			)
		)
		(property "Value" "SC10U16V5KX-7-GP-U"
			(at -0.0762 -6.1214 90)
			(unlocked yes)
			(layer "F.Fab")
			(hide yes)
			(effects
				(font
					(size 1.016 1.016)
					(thickness 0.1524)
				)
			)
		)
		(property "Device Type" "C805H58"
			(at -0.0762 -8.1534 90)
			(unlocked yes)
			(layer "F.Fab")
			(hide yes)
			(effects
				(font
					(size 1.016 1.016)
					(thickness 0.1524)
				)
			)
		)
		(duplicate_pad_numbers_are_jumpers no)
		(fp_line
			(start 0.635 0)
			(end -0.635 0)
			(stroke
				(width 0.508)
				(type default)
			)
			(layer "F.SilkS")
		)
		(fp_rect
			(start -0.9652 1.778)
			(end 0.9652 -1.778)
			(stroke
				(width 0)
				(type default)
			)
			(fill no)
			(layer "F.CrtYd")
		)
		(fp_poly
			(pts
				(xy -0.9652 -1.778) (xy 0.9652 -1.778) (xy 0.9652 1.778) (xy -0.9652 1.778)
			)
			(stroke
				(width 0)
				(type default)
			)
			(fill no)
			(layer "F.Fab")
		)
		(pad "1" smd rect
			(at 0 -0.9652 90)
			(size 1.397 1.143)
			(layers "F.Cu" "F.Mask" "F.Paste")
			(net "P12V_A_VIN_U22")
		)
		(pad "2" smd rect
			(at 0 0.9652 90)
			(size 1.397 1.143)
			(layers "F.Cu" "F.Mask" "F.Paste")
			(net "GND")
		)
	)
	(footprint ""
		(layer "F.Cu")
		(at 109.356652 -127.779272 180)
		(property "Reference" "Q242"
			(at 0 0 180)
			(layer "F.SilkS")
			(hide yes)
			(effects
				(font
					(size 1.27 1.27)
				)
			)
		)
		(property "Value" "2N7002K-2-GP"
			(at 0.127 -8.9662 180)
			(unlocked yes)
			(layer "F.Fab")
			(hide yes)
			(effects
				(font
					(size 1.016 1.016)
					(thickness 0.1524)
				)
			)
		)
		(property "Device Type" "SOT23DGS2D4H44"
			(at 0.127 -10.4902 180)
			(unlocked yes)
			(layer "F.Fab")
			(hide yes)
			(effects
				(font
					(size 1.016 1.016)
					(thickness 0.1524)
				)
			)
		)
		(duplicate_pad_numbers_are_jumpers no)
		(fp_line
			(start 1.651 1.778)
			(end 1.651 -1.778)
			(stroke
				(width 0.1524)
				(type default)
			)
			(layer "F.SilkS")
		)
		(fp_line
			(start 1.651 -1.778)
			(end -1.651 -1.778)
			(stroke
				(width 0.1524)
				(type default)
			)
			(layer "F.SilkS")
		)
		(fp_line
			(start -1.651 1.778)
			(end 1.651 1.778)
			(stroke
				(width 0.1524)
				(type default)
			)
			(layer "F.SilkS")
		)
		(fp_line
			(start -1.651 -1.778)
			(end -1.651 1.778)
			(stroke
				(width 0.1524)
				(type default)
			)
			(layer "F.SilkS")
		)
		(fp_poly
			(pts
				(xy -1.778 1.8796) (xy -1.778 -1.8796) (xy 1.778 -1.8796) (xy 1.778 1.8796)
			)
			(stroke
				(width 0)
				(type default)
			)
			(fill no)
			(layer "F.CrtYd")
		)
		(fp_poly
			(pts
				(xy -1.778 1.8796) (xy -1.778 -1.8796) (xy 1.778 -1.8796) (xy 1.778 1.8796)
			)
			(stroke
				(width 0)
				(type default)
			)
			(fill no)
			(layer "F.Fab")
		)
		(pad "D" smd custom
			(at 0 -0.9525 180)
			(size 0.1905 0.1905)
			(layers "F.Cu" "F.Mask" "F.Paste")
			(net "FLT_HDD15_N")
			(options
				(clearance outline)
				(anchor circle)
			)
			(primitives
				(gr_poly
					(pts
						(arc
							(start -0.1778 0.5715)
							(mid -0.321484 0.511984)
							(end -0.381 0.3683)
						)
						(arc
							(start -0.381 -0.3683)
							(mid -0.321484 -0.511984)
							(end -0.1778 -0.5715)
						)
						(arc
							(start 0.1778 -0.5715)
							(mid 0.321484 -0.511984)
							(end 0.381 -0.3683)
						)
						(arc
							(start 0.381 0.3683)
							(mid 0.321484 0.511984)
							(end 0.1778 0.5715)
						)
					)
					(width 0)
					(fill yes)
				)
			)
		)
		(pad "G" smd custom
			(at -0.98425 0.9525 180)
			(size 0.1905 0.1905)
			(layers "F.Cu" "F.Mask" "F.Paste")
			(net "DRIVE_A_15_FLT_LED")
			(options
				(clearance outline)
				(anchor circle)
			)
			(primitives
				(gr_poly
					(pts
						(arc
							(start -0.1778 0.5715)
							(mid -0.321484 0.511984)
							(end -0.381 0.3683)
						)
						(arc
							(start -0.381 -0.3683)
							(mid -0.321484 -0.511984)
							(end -0.1778 -0.5715)
						)
						(arc
							(start 0.1778 -0.5715)
							(mid 0.321484 -0.511984)
							(end 0.381 -0.3683)
						)
						(arc
							(start 0.381 0.3683)
							(mid 0.321484 0.511984)
							(end 0.1778 0.5715)
						)
					)
					(width 0)
					(fill yes)
				)
			)
		)
		(pad "S" smd custom
			(at 0.98425 0.9525 180)
			(size 0.1905 0.1905)
			(layers "F.Cu" "F.Mask" "F.Paste")
			(net "GND")
			(options
				(clearance outline)
				(anchor circle)
			)
			(primitives
				(gr_poly
					(pts
						(arc
							(start -0.1778 0.5715)
							(mid -0.321484 0.511984)
							(end -0.381 0.3683)
						)
						(arc
							(start -0.381 -0.3683)
							(mid -0.321484 -0.511984)
							(end -0.1778 -0.5715)
						)
						(arc
							(start 0.1778 -0.5715)
							(mid 0.321484 -0.511984)
							(end 0.381 -0.3683)
						)
						(arc
							(start 0.381 0.3683)
							(mid 0.321484 0.511984)
							(end 0.1778 0.5715)
						)
					)
					(width 0)
					(fill yes)
				)
			)
		)
	)
	(footprint ""
		(layer "F.Cu")
		(at 393.674854 -322.799964)
		(property "Reference" ""
			(at 0 0 0)
			(layer "F.SilkS")
			(hide yes)
			(effects
				(font
					(size 1.27 1.27)
				)
			)
		)
		(property "Value" "*"
			(at -8.398764 -8.057642 0)
			(unlocked yes)
			(layer "F.Fab")
			(hide yes)
			(effects
				(font
					(size 1.016 1.016)
					(thickness 0.1524)
				)
			)
		)
		(duplicate_pad_numbers_are_jumpers no)
		(fp_poly
			(pts
				(arc
					(start 7.3152 0)
					(mid 0 7.3152)
					(end -7.3152 0)
				)
				(arc
					(start -7.3152 -5.9944)
					(mid 0 -13.3096)
					(end 7.3152 -5.9944)
				)
			)
			(stroke
				(width 0)
				(type default)
			)
			(fill no)
			(layer "B.CrtYd")
		)
		(fp_poly
			(pts
				(arc
					(start 7.3152 0)
					(mid 0 7.3152)
					(end -7.3152 0)
				)
				(arc
					(start -7.3152 -5.9944)
					(mid 0 -13.3096)
					(end 7.3152 -5.9944)
				)
			)
			(stroke
				(width 0)
				(type default)
			)
			(fill no)
			(layer "F.CrtYd")
		)
		(fp_poly
			(pts
				(arc
					(start 7.3152 0)
					(mid 0 7.3152)
					(end -7.3152 0)
				)
				(arc
					(start -7.3152 -5.9944)
					(mid 0 -13.3096)
					(end 7.3152 -5.9944)
				)
			)
			(stroke
				(width 0)
				(type default)
			)
			(fill no)
			(layer "B.Fab")
		)
		(fp_poly
			(pts
				(arc
					(start 7.3152 0)
					(mid 0 7.3152)
					(end -7.3152 0)
				)
				(arc
					(start -7.3152 -5.9944)
					(mid 0 -13.3096)
					(end 7.3152 -5.9944)
				)
			)
			(stroke
				(width 0)
				(type default)
			)
			(fill no)
			(layer "F.Fab")
		)
		(pad "1" thru_hole oval
			(at 0 0)
			(size 14.0208 20.0152)
			(drill 0.0254
				(offset 0 -2.9972)
			)
			(layers "*.Cu" "*.Mask")
			(remove_unused_layers no)
			(net "Net_96")
			(clearance -1.002284)
			(thermal_gap 0.1524)
			(padstack
				(mode front_inner_back)
				(layer "Inner"
					(shape custom)
					(size 2.928012 2.928012)
					(options
						(anchor circle)
					)
					(primitives
						(gr_poly
							(pts
								(arc
									(start 4.571746 -2.084324)
									(mid 0.000333 7.430372)
									(end -4.571492 -2.084324)
								)
								(arc
									(start -4.571492 -2.084324)
									(mid -3.570296 -3.611977)
									(end -2.875026 -5.30098)
								)
								(arc
									(start -2.875026 -5.30098)
									(mid 0.000217 -7.43089)
									(end 2.87528 -5.30098)
								)
								(arc
									(start 2.87528 -5.30098)
									(mid 3.570511 -3.611956)
									(end 4.571746 -2.084324)
								)
							)
							(width 0)
							(fill yes)
						)
					)
					(clearance 0.1524)
				)
				(layer "B.Cu"
					(shape oval)
					(size 14.0208 20.0152)
					(offset 0 -2.9972)
					(clearance -1.002284)
				)
			)
		)
		(zone
			(layers "F.Cu" "B.Cu" "In1.Cu" "In2.Cu" "In3.Cu" "In4.Cu" "In5.Cu" "In6.Cu"
				"In7.Cu" "In8.Cu" "In9.Cu" "In10.Cu"
			)
			(hatch none 0.5)
			(connect_pads
				(clearance 0)
			)
			(min_thickness 0.25)
			(keepout
				(tracks not_allowed)
				(vias allowed)
				(pads allowed)
				(copperpour not_allowed)
				(footprints allowed)
			)
			(placement
				(enabled no)
				(sheetname "")
			)
			(fill
				(thermal_gap 0.5)
				(thermal_bridge_width 0.5)
				(island_removal_mode 0)
			)
			(polygon
				(pts
					(arc
						(start 386.664454 -328.794364)
						(mid 393.674854 -335.804764)
						(end 400.685254 -328.794364)
					)
					(arc
						(start 400.685254 -322.799964)
						(mid 393.674854 -315.789564)
						(end 386.664454 -322.799964)
					)
				)
			)
		)
	)
	(footprint ""
		(layer "F.Cu")
		(at 370.259102 -287.851342 90)
		(property "Reference" "C140"
			(at 0 0 90)
			(layer "F.SilkS")
			(hide yes)
			(effects
				(font
					(size 1.27 1.27)
				)
			)
		)
		(property "Value" "SCD033U25V2KX-GP"
			(at 1.1811 -2.7051 90)
			(unlocked yes)
			(layer "F.Fab")
			(hide yes)
			(effects
				(font
					(size 1.016 1.016)
					(thickness 0.1524)
				)
			)
		)
		(property "Device Type" "C402H22"
			(at 1.1811 -4.2291 90)
			(unlocked yes)
			(layer "F.Fab")
			(hide yes)
			(effects
				(font
					(size 1.016 1.016)
					(thickness 0.1524)
				)
			)
		)
		(duplicate_pad_numbers_are_jumpers no)
		(fp_rect
			(start -0.4318 0.9525)
			(end 0.4318 -0.9525)
			(stroke
				(width 0)
				(type default)
			)
			(fill no)
			(layer "F.CrtYd")
		)
		(fp_rect
			(start -0.4318 0.9525)
			(end 0.4318 -0.9525)
			(stroke
				(width 0)
				(type default)
			)
			(fill no)
			(layer "F.Fab")
		)
		(pad "1" smd custom
			(at 0 -0.4445 90)
			(size 0.1524 0.1524)
			(layers "F.Cu" "F.Mask" "F.Paste")
			(net "P12V_A")
			(options
				(clearance outline)
				(anchor circle)
			)
			(primitives
				(gr_poly
					(pts
						(arc
							(start 0.3048 -0.2032)
							(mid 0.275042 -0.275042)
							(end 0.2032 -0.3048)
						)
						(arc
							(start -0.2032 -0.3048)
							(mid -0.275042 -0.275042)
							(end -0.3048 -0.2032)
						)
						(arc
							(start -0.3048 0.2032)
							(mid -0.275042 0.275042)
							(end -0.2032 0.3048)
						)
						(arc
							(start 0.2032 0.3048)
							(mid 0.275042 0.275042)
							(end 0.3048 0.2032)
						)
					)
					(width 0)
					(fill yes)
				)
			)
		)
		(pad "2" smd custom
			(at 0 0.4445 90)
			(size 0.1524 0.1524)
			(layers "F.Cu" "F.Mask" "F.Paste")
			(net "SW_HDD_N7")
			(options
				(clearance outline)
				(anchor circle)
			)
			(primitives
				(gr_poly
					(pts
						(arc
							(start 0.3048 -0.2032)
							(mid 0.275042 -0.275042)
							(end 0.2032 -0.3048)
						)
						(arc
							(start -0.2032 -0.3048)
							(mid -0.275042 -0.275042)
							(end -0.3048 -0.2032)
						)
						(arc
							(start -0.3048 0.2032)
							(mid -0.275042 0.275042)
							(end -0.2032 0.3048)
						)
						(arc
							(start 0.2032 0.3048)
							(mid 0.275042 0.275042)
							(end 0.3048 0.2032)
						)
					)
					(width 0)
					(fill yes)
				)
			)
		)
	)
	(footprint ""
		(layer "F.Cu")
		(at 363.020102 -188.954918 180)
		(property "Reference" "C291"
			(at 0 0 180)
			(layer "F.SilkS")
			(hide yes)
			(effects
				(font
					(size 1.27 1.27)
				)
			)
		)
		(property "Value" "SC4D7U25V5KX-1-GP"
			(at -0.0762 -6.1214 180)
			(unlocked yes)
			(layer "F.Fab")
			(hide yes)
			(effects
				(font
					(size 1.016 1.016)
					(thickness 0.1524)
				)
			)
		)
		(property "Device Type" "C805H58"
			(at -0.0762 -8.1534 180)
			(unlocked yes)
			(layer "F.Fab")
			(hide yes)
			(effects
				(font
					(size 1.016 1.016)
					(thickness 0.1524)
				)
			)
		)
		(duplicate_pad_numbers_are_jumpers no)
		(fp_line
			(start 0.635 0)
			(end -0.635 0)
			(stroke
				(width 0.508)
				(type default)
			)
			(layer "F.SilkS")
		)
		(fp_rect
			(start -0.9652 1.778)
			(end 0.9652 -1.778)
			(stroke
				(width 0)
				(type default)
			)
			(fill no)
			(layer "F.CrtYd")
		)
		(fp_poly
			(pts
				(xy -0.9652 -1.778) (xy 0.9652 -1.778) (xy 0.9652 1.778) (xy -0.9652 1.778)
			)
			(stroke
				(width 0)
				(type default)
			)
			(fill no)
			(layer "F.Fab")
		)
		(pad "1" smd rect
			(at 0 -0.9652 180)
			(size 1.397 1.143)
			(layers "F.Cu" "F.Mask" "F.Paste")
			(net "P12V_HDD19")
		)
		(pad "2" smd rect
			(at 0 0.9652 180)
			(size 1.397 1.143)
			(layers "F.Cu" "F.Mask" "F.Paste")
			(net "GND")
		)
	)
)
